(kicad_pcb
	(version 20241229)
	(generator "pcbnew")
	(generator_version "9.0")
	(general
		(thickness 0.876)
		(legacy_teardrops no)
	)
	(paper "A4")
	(title_block
		(rev "1.2.2")
		(comment 9 "footprints 11-15 of 20")
	)
	(layers
		(0 "F.Cu" signal)
		(4 "In1.Cu" signal)
		(6 "In2.Cu" signal)
		(2 "B.Cu" signal)
		(9 "F.Adhes" user "F.Adhesive")
		(11 "B.Adhes" user "B.Adhesive")
		(13 "F.Paste" user)
		(15 "B.Paste" user)
		(5 "F.SilkS" user "F.Silkscreen")
		(7 "B.SilkS" user "B.Silkscreen")
		(1 "F.Mask" user)
		(3 "B.Mask" user)
		(17 "Dwgs.User" user "User.Drawings")
		(19 "Cmts.User" user "User.Comments")
		(21 "Eco1.User" user "User.Eco1")
		(23 "Eco2.User" user "User.Eco2")
		(25 "Edge.Cuts" user)
		(27 "Margin" user)
		(31 "F.CrtYd" user "F.Courtyard")
		(29 "B.CrtYd" user "B.Courtyard")
		(35 "F.Fab" user)
		(33 "B.Fab" user)
	)
	(footprint "antmicro-footprints:C_0603_1608Metric"
		(layer "B.Cu")
		(at 137.320059 114.017277 180)
		(descr "Capacitor SMD 0603")
		(tags "capacitor 0603")
		(property "Reference" "C6"
			(at 1.82 -0.02 0)
			(layer "B.SilkS")
			(effects
				(font
					(size 0.7 0.7)
					(thickness 0.15)
				)
				(justify mirror)
			)
		)
		(property "Value" "C_1u_0603"
			(at 0 -1.9 0)
			(layer "B.Fab")
			(effects
				(font
					(size 1 1)
					(thickness 0.15)
				)
				(justify mirror)
			)
		)
		(property "Datasheet" "https://spicat.kyocera-avx.com/product/mlcc/chartview/0603YD105KAT2A/"
			(at 0 0 180)
			(layer "F.Fab")
			(hide yes)
			(effects
				(font
					(size 1.27 1.27)
					(thickness 0.15)
				)
			)
		)
		(property "Description" "SMD Multilayer Ceramic Capacitor, 1 µF, 16 V, 0603 [1608 Metric], ± 10%, X5R, AVX 0603 MLCC"
			(at 0 0 180)
			(layer "F.Fab")
			(hide yes)
			(effects
				(font
					(size 1.27 1.27)
					(thickness 0.15)
				)
			)
		)
		(property "Author" "Antmicro"
			(at 274.640118 228.034554 0)
			(layer "B.Fab")
			(hide yes)
			(effects
				(font
					(size 1 1)
					(thickness 0.15)
				)
				(justify mirror)
			)
		)
		(property "Dielectric" ""
			(at 274.640118 228.034554 0)
			(layer "B.Fab")
			(hide yes)
			(effects
				(font
					(size 1 1)
					(thickness 0.15)
				)
				(justify mirror)
			)
		)
		(property "License" "Apache-2.0"
			(at 274.640118 228.034554 0)
			(layer "B.Fab")
			(hide yes)
			(effects
				(font
					(size 1 1)
					(thickness 0.15)
				)
				(justify mirror)
			)
		)
		(property "MPN" "0603YD105KAT2A"
			(at 274.640118 228.034554 0)
			(layer "B.Fab")
			(hide yes)
			(effects
				(font
					(size 1 1)
					(thickness 0.15)
				)
				(justify mirror)
			)
		)
		(property "Manufacturer" "KYOCERA AVX"
			(at 274.640118 228.034554 0)
			(layer "B.Fab")
			(hide yes)
			(effects
				(font
					(size 1 1)
					(thickness 0.15)
				)
				(justify mirror)
			)
		)
		(property "Public" "False"
			(at 274.640118 228.034554 0)
			(layer "B.Fab")
			(hide yes)
			(effects
				(font
					(size 1 1)
					(thickness 0.15)
				)
				(justify mirror)
			)
		)
		(property "Val" "1u"
			(at 274.640118 228.034554 0)
			(layer "B.Fab")
			(hide yes)
			(effects
				(font
					(size 1 1)
					(thickness 0.15)
				)
				(justify mirror)
			)
		)
		(property "Voltage" ""
			(at 274.640118 228.034554 0)
			(layer "B.Fab")
			(hide yes)
			(effects
				(font
					(size 1 1)
					(thickness 0.15)
				)
				(justify mirror)
			)
		)
		(sheetname "/")
		(sheetfile "m2-pcie-adapter.kicad_sch")
		(attr smd)
		(fp_line
			(start -0.15 0.4)
			(end 0.15 0.4)
			(stroke
				(width 0.15)
				(type solid)
			)
			(layer "B.SilkS")
		)
		(fp_line
			(start -0.15 -0.4)
			(end 0.15 -0.4)
			(stroke
				(width 0.15)
				(type solid)
			)
			(layer "B.SilkS")
		)
		(fp_rect
			(start -1.25 0.65)
			(end 1.25 -0.65)
			(stroke
				(width 0.05)
				(type solid)
			)
			(fill no)
			(layer "B.CrtYd")
		)
		(fp_rect
			(start -0.8 0.4)
			(end 0.8 -0.4)
			(stroke
				(width 0.15)
				(type solid)
			)
			(fill no)
			(layer "B.Fab")
		)
		(pad "1" smd roundrect
			(at -0.7 0 180)
			(size 0.8 1)
			(layers "B.Cu" "B.Mask" "B.Paste")
			(roundrect_rratio 0.2)
			(net 62 "/+3V3_AUX")
			(pintype "passive")
		)
		(pad "2" smd roundrect
			(at 0.7 0 180)
			(size 0.8 1)
			(layers "B.Cu" "B.Mask" "B.Paste")
			(roundrect_rratio 0.2)
			(net 60 "GND")
			(pintype "passive")
		)
	)
	(footprint "antmicro-footprints:C_0603_1608Metric"
		(layer "B.Cu")
		(at 142.500059 114.017277)
		(descr "Capacitor SMD 0603")
		(tags "capacitor 0603")
		(property "Reference" "C3"
			(at -0.1 -3.67 0)
			(layer "B.SilkS")
			(effects
				(font
					(size 0.7 0.7)
					(thickness 0.15)
				)
				(justify mirror)
			)
		)
		(property "Value" "C_1u_0603"
			(at 0 -1.9 0)
			(layer "B.Fab")
			(effects
				(font
					(size 1 1)
					(thickness 0.15)
				)
				(justify mirror)
			)
		)
		(property "Datasheet" "https://spicat.kyocera-avx.com/product/mlcc/chartview/0603YD105KAT2A/"
			(at 0 0 0)
			(layer "F.Fab")
			(hide yes)
			(effects
				(font
					(size 1.27 1.27)
					(thickness 0.15)
				)
			)
		)
		(property "Description" "SMD Multilayer Ceramic Capacitor, 1 µF, 16 V, 0603 [1608 Metric], ± 10%, X5R, AVX 0603 MLCC"
			(at 0 0 0)
			(layer "F.Fab")
			(hide yes)
			(effects
				(font
					(size 1.27 1.27)
					(thickness 0.15)
				)
			)
		)
		(property "Author" "Antmicro"
			(at 0 0 0)
			(layer "B.Fab")
			(hide yes)
			(effects
				(font
					(size 1 1)
					(thickness 0.15)
				)
				(justify mirror)
			)
		)
		(property "Dielectric" ""
			(at 0 0 0)
			(layer "B.Fab")
			(hide yes)
			(effects
				(font
					(size 1 1)
					(thickness 0.15)
				)
				(justify mirror)
			)
		)
		(property "License" "Apache-2.0"
			(at 0 0 0)
			(layer "B.Fab")
			(hide yes)
			(effects
				(font
					(size 1 1)
					(thickness 0.15)
				)
				(justify mirror)
			)
		)
		(property "MPN" "0603YD105KAT2A"
			(at 0 0 0)
			(layer "B.Fab")
			(hide yes)
			(effects
				(font
					(size 1 1)
					(thickness 0.15)
				)
				(justify mirror)
			)
		)
		(property "Manufacturer" "KYOCERA AVX"
			(at 0 0 0)
			(layer "B.Fab")
			(hide yes)
			(effects
				(font
					(size 1 1)
					(thickness 0.15)
				)
				(justify mirror)
			)
		)
		(property "Public" "False"
			(at 0 0 0)
			(layer "B.Fab")
			(hide yes)
			(effects
				(font
					(size 1 1)
					(thickness 0.15)
				)
				(justify mirror)
			)
		)
		(property "Val" "1u"
			(at 0 0 0)
			(layer "B.Fab")
			(hide yes)
			(effects
				(font
					(size 1 1)
					(thickness 0.15)
				)
				(justify mirror)
			)
		)
		(property "Voltage" ""
			(at 0 0 0)
			(layer "B.Fab")
			(hide yes)
			(effects
				(font
					(size 1 1)
					(thickness 0.15)
				)
				(justify mirror)
			)
		)
		(sheetname "/")
		(sheetfile "m2-pcie-adapter.kicad_sch")
		(attr smd)
		(fp_line
			(start -0.15 -0.4)
			(end 0.15 -0.4)
			(stroke
				(width 0.15)
				(type solid)
			)
			(layer "B.SilkS")
		)
		(fp_line
			(start -0.15 0.4)
			(end 0.15 0.4)
			(stroke
				(width 0.15)
				(type solid)
			)
			(layer "B.SilkS")
		)
		(fp_rect
			(start -1.25 0.65)
			(end 1.25 -0.65)
			(stroke
				(width 0.05)
				(type solid)
			)
			(fill no)
			(layer "B.CrtYd")
		)
		(fp_rect
			(start -0.8 0.4)
			(end 0.8 -0.4)
			(stroke
				(width 0.15)
				(type solid)
			)
			(fill no)
			(layer "B.Fab")
		)
		(pad "1" smd roundrect
			(at -0.7 0)
			(size 0.8 1)
			(layers "B.Cu" "B.Mask" "B.Paste")
			(roundrect_rratio 0.2)
			(net 31 "/+3V3")
			(pintype "passive")
		)
		(pad "2" smd roundrect
			(at 0.7 0)
			(size 0.8 1)
			(layers "B.Cu" "B.Mask" "B.Paste")
			(roundrect_rratio 0.2)
			(net 60 "GND")
			(pintype "passive")
		)
	)
	(footprint "antmicro-footprints:Conn_Molex_KK_1x4_22-05-3041_Horizontal"
		(layer "B.Cu")
		(at 175.590059 96.137277 180)
		(property "Reference" "J3"
			(at 0 1.95 0)
			(layer "B.SilkS")
			(effects
				(font
					(size 0.7 0.7)
					(thickness 0.15)
				)
				(justify left bottom mirror)
			)
		)
		(property "Value" "Molex_KK_1x4_22-05-3041_Horizontal"
			(at 0 -14 0)
			(layer "B.Fab")
			(effects
				(font
					(size 0.7 0.7)
					(thickness 0.15)
				)
				(justify left bottom mirror)
			)
		)
		(property "Datasheet" "https://www.molex.com/content/dam/molex/molex-dot-com/products/automated/en-us/salesdrawingpdf/747/7478/022053041_sd.pdf?inline"
			(at 0 0 180)
			(layer "F.Fab")
			(hide yes)
			(effects
				(font
					(size 1.27 1.27)
					(thickness 0.15)
				)
			)
		)
		(property "Description" "Connector Header, THT,  4x1"
			(at 0 0 180)
			(layer "F.Fab")
			(hide yes)
			(effects
				(font
					(size 1.27 1.27)
					(thickness 0.15)
				)
			)
		)
		(property "Author" "Antmicro"
			(at 351.180118 192.274554 0)
			(layer "B.Fab")
			(hide yes)
			(effects
				(font
					(size 1 1)
					(thickness 0.15)
				)
				(justify mirror)
			)
		)
		(property "License" "Apache-2.0"
			(at 351.180118 192.274554 0)
			(layer "B.Fab")
			(hide yes)
			(effects
				(font
					(size 1 1)
					(thickness 0.15)
				)
				(justify mirror)
			)
		)
		(property "MPN" "22-05-3041"
			(at 351.180118 192.274554 0)
			(layer "B.Fab")
			(hide yes)
			(effects
				(font
					(size 1 1)
					(thickness 0.15)
				)
				(justify mirror)
			)
		)
		(property "Manufacturer" "Molex"
			(at 351.180118 192.274554 0)
			(layer "B.Fab")
			(hide yes)
			(effects
				(font
					(size 1 1)
					(thickness 0.15)
				)
				(justify mirror)
			)
		)
		(sheetname "/")
		(sheetfile "m2-pcie-adapter.kicad_sch")
		(attr through_hole dnp)
		(fp_line
			(start 8.9 1.55)
			(end 8.9 1.05)
			(stroke
				(width 0.15)
				(type solid)
			)
			(layer "B.SilkS")
		)
		(fp_line
			(start 8.9 1.55)
			(end 8.4 1.55)
			(stroke
				(width 0.15)
				(type solid)
			)
			(layer "B.SilkS")
		)
		(fp_line
			(start -1.275 1.525)
			(end -0.775 1.525)
			(stroke
				(width 0.15)
				(type solid)
			)
			(layer "B.SilkS")
		)
		(fp_line
			(start -1.275 1.525)
			(end -1.275 1.025)
			(stroke
				(width 0.15)
				(type solid)
			)
			(layer "B.SilkS")
		)
		(fp_line
			(start -1.3 -3.3)
			(end -0.8 -3.3)
			(stroke
				(width 0.15)
				(type solid)
			)
			(layer "B.SilkS")
		)
		(fp_line
			(start -1.3 -3.3)
			(end -1.3 -2.8)
			(stroke
				(width 0.15)
				(type solid)
			)
			(layer "B.SilkS")
		)
		(fp_circle
			(center -0.9 -1.8)
			(end -0.85 -1.8)
			(stroke
				(width 0.15)
				(type solid)
			)
			(fill yes)
			(layer "B.SilkS")
		)
		(fp_rect
			(start -1.6 1.7)
			(end 9.2 -12.94)
			(stroke
				(width 0.05)
				(type solid)
			)
			(fill no)
			(layer "B.CrtYd")
		)
		(fp_line
			(start 8.81 1.425)
			(end 8.81 -3.17)
			(stroke
				(width 0.15)
				(type solid)
			)
			(layer "B.Fab")
		)
		(fp_line
			(start -1.2 1.425)
			(end -1.2 -3.17)
			(stroke
				(width 0.15)
				(type solid)
			)
			(layer "B.Fab")
		)
		(fp_line
			(start -1.2 -3.17)
			(end 8.81 -3.17)
			(stroke
				(width 0.15)
				(type solid)
			)
			(layer "B.Fab")
		)
		(fp_line
			(start -1.225 1.425)
			(end 8.785 1.425)
			(stroke
				(width 0.15)
				(type solid)
			)
			(layer "B.Fab")
		)
		(pad "1" thru_hole circle
			(at 0 0 180)
			(size 2.02 2.02)
			(drill 1.02)
			(layers "*.Cu" "*.Mask")
			(remove_unused_layers no)
			(net 30 "+12V")
			(pintype "passive")
		)
		(pad "2" thru_hole circle
			(at 2.54 0 180)
			(size 2.02 2.02)
			(drill 1.02)
			(layers "*.Cu" "*.Mask")
			(remove_unused_layers no)
			(net 60 "GND")
			(pintype "passive")
		)
		(pad "3" thru_hole circle
			(at 5.08 0 180)
			(size 2.02 2.02)
			(drill 1.02)
			(layers "*.Cu" "*.Mask")
			(remove_unused_layers no)
			(net 60 "GND")
			(pintype "passive")
		)
		(pad "4" thru_hole circle
			(at 7.62 0 180)
			(size 2.02 2.02)
			(drill 1.02)
			(layers "*.Cu" "*.Mask")
			(remove_unused_layers no)
			(net 61 "+5V")
			(pintype "passive")
		)
	)
	(footprint "antmicro-footprints:C_0603_1608Metric"
		(layer "B.Cu")
		(at 142.500059 112.497277)
		(descr "Capacitor SMD 0603")
		(tags "capacitor 0603")
		(property "Reference" "C8"
			(at -0.1 -3.05 0)
			(layer "B.SilkS")
			(effects
				(font
					(size 0.7 0.7)
					(thickness 0.15)
				)
				(justify mirror)
			)
		)
		(property "Value" "C_1u_0603"
			(at 0 -1.9 0)
			(layer "B.Fab")
			(effects
				(font
					(size 1 1)
					(thickness 0.15)
				)
				(justify mirror)
			)
		)
		(property "Datasheet" "https://spicat.kyocera-avx.com/product/mlcc/chartview/0603YD105KAT2A/"
			(at 0 0 0)
			(layer "F.Fab")
			(hide yes)
			(effects
				(font
					(size 1.27 1.27)
					(thickness 0.15)
				)
			)
		)
		(property "Description" "SMD Multilayer Ceramic Capacitor, 1 µF, 16 V, 0603 [1608 Metric], ± 10%, X5R, AVX 0603 MLCC"
			(at 0 0 0)
			(layer "F.Fab")
			(hide yes)
			(effects
				(font
					(size 1.27 1.27)
					(thickness 0.15)
				)
			)
		)
		(property "Author" "Antmicro"
			(at 0 0 0)
			(layer "B.Fab")
			(hide yes)
			(effects
				(font
					(size 1 1)
					(thickness 0.15)
				)
				(justify mirror)
			)
		)
		(property "Dielectric" ""
			(at 0 0 0)
			(layer "B.Fab")
			(hide yes)
			(effects
				(font
					(size 1 1)
					(thickness 0.15)
				)
				(justify mirror)
			)
		)
		(property "License" "Apache-2.0"
			(at 0 0 0)
			(layer "B.Fab")
			(hide yes)
			(effects
				(font
					(size 1 1)
					(thickness 0.15)
				)
				(justify mirror)
			)
		)
		(property "MPN" "0603YD105KAT2A"
			(at 0 0 0)
			(layer "B.Fab")
			(hide yes)
			(effects
				(font
					(size 1 1)
					(thickness 0.15)
				)
				(justify mirror)
			)
		)
		(property "Manufacturer" "KYOCERA AVX"
			(at 0 0 0)
			(layer "B.Fab")
			(hide yes)
			(effects
				(font
					(size 1 1)
					(thickness 0.15)
				)
				(justify mirror)
			)
		)
		(property "Public" "False"
			(at 0 0 0)
			(layer "B.Fab")
			(hide yes)
			(effects
				(font
					(size 1 1)
					(thickness 0.15)
				)
				(justify mirror)
			)
		)
		(property "Val" "1u"
			(at 0 0 0)
			(layer "B.Fab")
			(hide yes)
			(effects
				(font
					(size 1 1)
					(thickness 0.15)
				)
				(justify mirror)
			)
		)
		(property "Voltage" ""
			(at 0 0 0)
			(layer "B.Fab")
			(hide yes)
			(effects
				(font
					(size 1 1)
					(thickness 0.15)
				)
				(justify mirror)
			)
		)
		(sheetname "/")
		(sheetfile "m2-pcie-adapter.kicad_sch")
		(attr smd)
		(fp_line
			(start -0.15 -0.4)
			(end 0.15 -0.4)
			(stroke
				(width 0.15)
				(type solid)
			)
			(layer "B.SilkS")
		)
		(fp_line
			(start -0.15 0.4)
			(end 0.15 0.4)
			(stroke
				(width 0.15)
				(type solid)
			)
			(layer "B.SilkS")
		)
		(fp_rect
			(start -1.25 0.65)
			(end 1.25 -0.65)
			(stroke
				(width 0.05)
				(type solid)
			)
			(fill no)
			(layer "B.CrtYd")
		)
		(fp_rect
			(start -0.8 0.4)
			(end 0.8 -0.4)
			(stroke
				(width 0.15)
				(type solid)
			)
			(fill no)
			(layer "B.Fab")
		)
		(pad "1" smd roundrect
			(at -0.7 0)
			(size 0.8 1)
			(layers "B.Cu" "B.Mask" "B.Paste")
			(roundrect_rratio 0.2)
			(net 31 "/+3V3")
			(pintype "passive")
		)
		(pad "2" smd roundrect
			(at 0.7 0)
			(size 0.8 1)
			(layers "B.Cu" "B.Mask" "B.Paste")
			(roundrect_rratio 0.2)
			(net 60 "GND")
			(pintype "passive")
		)
	)
	(footprint "antmicro-footprints:C_0603_1608Metric"
		(layer "B.Cu")
		(at 139.890059 112.497277)
		(descr "Capacitor SMD 0603")
		(tags "capacitor 0603")
		(property "Reference" "C9"
			(at -0.05 -0.99 0)
			(layer "B.SilkS")
			(effects
				(font
					(size 0.7 0.7)
					(thickness 0.15)
				)
				(justify mirror)
			)
		)
		(property "Value" "C_1u_0603"
			(at 0 -1.9 0)
			(layer "B.Fab")
			(effects
				(font
					(size 1 1)
					(thickness 0.15)
				)
				(justify mirror)
			)
		)
		(property "Datasheet" "https://spicat.kyocera-avx.com/product/mlcc/chartview/0603YD105KAT2A/"
			(at 0 0 0)
			(layer "F.Fab")
			(hide yes)
			(effects
				(font
					(size 1.27 1.27)
					(thickness 0.15)
				)
			)
		)
		(property "Description" "SMD Multilayer Ceramic Capacitor, 1 µF, 16 V, 0603 [1608 Metric], ± 10%, X5R, AVX 0603 MLCC"
			(at 0 0 0)
			(layer "F.Fab")
			(hide yes)
			(effects
				(font
					(size 1.27 1.27)
					(thickness 0.15)
				)
			)
		)
		(property "Author" "Antmicro"
			(at 0 0 0)
			(layer "B.Fab")
			(hide yes)
			(effects
				(font
					(size 1 1)
					(thickness 0.15)
				)
				(justify mirror)
			)
		)
		(property "Dielectric" ""
			(at 0 0 0)
			(layer "B.Fab")
			(hide yes)
			(effects
				(font
					(size 1 1)
					(thickness 0.15)
				)
				(justify mirror)
			)
		)
		(property "License" "Apache-2.0"
			(at 0 0 0)
			(layer "B.Fab")
			(hide yes)
			(effects
				(font
					(size 1 1)
					(thickness 0.15)
				)
				(justify mirror)
			)
		)
		(property "MPN" "0603YD105KAT2A"
			(at 0 0 0)
			(layer "B.Fab")
			(hide yes)
			(effects
				(font
					(size 1 1)
					(thickness 0.15)
				)
				(justify mirror)
			)
		)
		(property "Manufacturer" "KYOCERA AVX"
			(at 0 0 0)
			(layer "B.Fab")
			(hide yes)
			(effects
				(font
					(size 1 1)
					(thickness 0.15)
				)
				(justify mirror)
			)
		)
		(property "Public" "False"
			(at 0 0 0)
			(layer "B.Fab")
			(hide yes)
			(effects
				(font
					(size 1 1)
					(thickness 0.15)
				)
				(justify mirror)
			)
		)
		(property "Val" "1u"
			(at 0 0 0)
			(layer "B.Fab")
			(hide yes)
			(effects
				(font
					(size 1 1)
					(thickness 0.15)
				)
				(justify mirror)
			)
		)
		(property "Voltage" ""
			(at 0 0 0)
			(layer "B.Fab")
			(hide yes)
			(effects
				(font
					(size 1 1)
					(thickness 0.15)
				)
				(justify mirror)
			)
		)
		(sheetname "/")
		(sheetfile "m2-pcie-adapter.kicad_sch")
		(attr smd)
		(fp_line
			(start -0.15 -0.4)
			(end 0.15 -0.4)
			(stroke
				(width 0.15)
				(type solid)
			)
			(layer "B.SilkS")
		)
		(fp_line
			(start -0.15 0.4)
			(end 0.15 0.4)
			(stroke
				(width 0.15)
				(type solid)
			)
			(layer "B.SilkS")
		)
		(fp_rect
			(start -1.25 0.65)
			(end 1.25 -0.65)
			(stroke
				(width 0.05)
				(type solid)
			)
			(fill no)
			(layer "B.CrtYd")
		)
		(fp_rect
			(start -0.8 0.4)
			(end 0.8 -0.4)
			(stroke
				(width 0.15)
				(type solid)
			)
			(fill no)
			(layer "B.Fab")
		)
		(pad "1" smd roundrect
			(at -0.7 0)
			(size 0.8 1)
			(layers "B.Cu" "B.Mask" "B.Paste")
			(roundrect_rratio 0.2)
			(net 31 "/+3V3")
			(pintype "passive")
		)
		(pad "2" smd roundrect
			(at 0.7 0)
			(size 0.8 1)
			(layers "B.Cu" "B.Mask" "B.Paste")
			(roundrect_rratio 0.2)
			(net 60 "GND")
			(pintype "passive")
		)
	)
)
